FILE_TYPE = MACRO_DRAWING;
SET COLOR_WIRE YELLOW;
SET COLOR_PROP ORANGE;
SET COLOR_DOT WHITE;
SET COLOR_ARC YELLOW;
SET COLOR_BODY GREEN;
SET COLOR_NOTE PURPLE;
SET PROP_DISPLAY VALUE;
SET PAGE_NUMBER P2;
FORCEADD QUANTA_TITLE_BLOCK_C..2
(-100 100);
FORCEPROP 1 LAST Q_TITLE TABLE OF CONTENT 1/3
J 0
(-9416 151);
DISPLAY 2.446809 (-9416 151);
PAINT GREEN (-9416 151);
FORCEPROP 1 LAST CUSTOM_TXT_CDS <CON_TC_SNM78>
J 0
(-5200 1975);
FORCEPROP 1 LAST CUSTOM_TXT_CDS <CON_TC_SNM77>
J 0
(-5200 2075);
FORCEPROP 1 LAST CUSTOM_TXT_CDS <CON_TC_SNO74>
J 2
(-5300 2375);
FORCEPROP 1 LAST CUSTOM_TXT_CDS <CON_TC_SNO75>
J 2
(-5300 2275);
FORCEPROP 1 LAST CUSTOM_TXT_CDS <CON_TC_SNO77>
J 2
(-5300 2075);
FORCEPROP 1 LAST CUSTOM_TXT_CDS <CON_TC_SNM119>
J 0
(-2700 1875);
FORCEPROP 1 LAST CUSTOM_TXT_CDS <CON_TC_SNO115>
J 2
(-2800 2275);
FORCEPROP 1 LAST CUSTOM_TXT_CDS <CON_TC_SNM63>
J 0
(-5200 3475);
FORCEPROP 1 LAST CUSTOM_TXT_CDS <CON_TC_SNM8>
J 0
(-7700 4975);
FORCEPROP 1 LAST CUSTOM_TXT_CDS <CON_TC_SNM57>
J 0
(-5200 4075);
FORCEPROP 1 LAST CUSTOM_TXT_CDS <CON_TC_SNO82>
J 2
(-2800 5575);
FORCEPROP 1 LAST CUSTOM_TXT_CDS <CON_TC_SNM37>
J 0
(-7700 2075);
FORCEPROP 1 LAST CUSTOM_TXT_CDS <CON_TC_SNM36>
J 0
(-7700 2175);
FORCEPROP 1 LAST CUSTOM_TXT_CDS <CON_TC_SNM35>
J 0
(-7700 2275);
FORCEPROP 1 LAST CUSTOM_TXT_CDS <CON_TC_SNM40>
J 0
(-7700 1775);
FORCEPROP 1 LAST CUSTOM_TXT_CDS <Q_REV>
J 0
(-275 200);
DISPLAY 1.212766 (-275 200);
FORCEPROP 1 LAST CUSTOM_TXT_CDS <CON_PAGE_NUM> OF <CON_TOTAL_PAGES>
J 0
(-538 113);
DISPLAY 0.978723 (-538 113);
FORCEPROP 1 LAST CUSTOM_TXT_CDS <CON_LAST_MODIFIED>
J 0
(-2000 125);
DISPLAY 0.978723 (-2000 125);
FORCEPROP 1 LAST CUSTOM_TXT_CDS <Q_NUMBER>
J 0
(-1500 200);
DISPLAY 1.212766 (-1500 200);
FORCEPROP 1 LAST CUSTOM_TXT_CDS <Q_PROJ>
J 0
(-2475 200);
DISPLAY 1.212766 (-2475 200);
FORCEPROP 1 LAST CUSTOM_TXT_CDS <CON_TC_SNM1>
J 0
(-7700 5675);
FORCEPROP 1 LAST CUSTOM_TXT_CDS <CON_TC_SNM2>
J 0
(-7700 5575);
FORCEPROP 1 LAST CUSTOM_TXT_CDS <CON_TC_SNM3>
J 0
(-7700 5475);
FORCEPROP 1 LAST CUSTOM_TXT_CDS <CON_TC_SNM4>
J 0
(-7700 5375);
FORCEPROP 1 LAST CUSTOM_TXT_CDS <CON_TC_SNM5>
J 0
(-7700 5275);
FORCEPROP 1 LAST CUSTOM_TXT_CDS <CON_TC_SNM6>
J 0
(-7700 5175);
FORCEPROP 1 LAST CUSTOM_TXT_CDS <CON_TC_SNM7>
J 0
(-7700 5075);
FORCEPROP 1 LAST CUSTOM_TXT_CDS <CON_TC_SNM9>
J 0
(-7700 4875);
FORCEPROP 1 LAST CUSTOM_TXT_CDS <CON_TC_SNM10>
J 0
(-7700 4775);
FORCEPROP 1 LAST CUSTOM_TXT_CDS <CON_TC_SNM11>
J 0
(-7700 4675);
FORCEPROP 1 LAST CUSTOM_TXT_CDS <CON_TC_SNM12>
J 0
(-7700 4575);
FORCEPROP 1 LAST CUSTOM_TXT_CDS <CON_TC_SNM13>
J 0
(-7700 4475);
FORCEPROP 1 LAST CUSTOM_TXT_CDS <CON_TC_SNM14>
J 0
(-7700 4375);
FORCEPROP 1 LAST CUSTOM_TXT_CDS <CON_TC_SNM15>
J 0
(-7700 4275);
FORCEPROP 1 LAST CUSTOM_TXT_CDS <CON_TC_SNM16>
J 0
(-7700 4175);
FORCEPROP 1 LAST CUSTOM_TXT_CDS <CON_TC_SNM17>
J 0
(-7700 4075);
FORCEPROP 1 LAST CUSTOM_TXT_CDS <CON_TC_SNM18>
J 0
(-7700 3975);
FORCEPROP 1 LAST CUSTOM_TXT_CDS <CON_TC_SNM19>
J 0
(-7700 3875);
FORCEPROP 1 LAST CUSTOM_TXT_CDS <CON_TC_SNM20>
J 0
(-7700 3775);
FORCEPROP 1 LAST CUSTOM_TXT_CDS <CON_TC_SNM21>
J 0
(-7700 3675);
FORCEPROP 1 LAST CUSTOM_TXT_CDS <CON_TC_SNM22>
J 0
(-7700 3575);
FORCEPROP 1 LAST CUSTOM_TXT_CDS <CON_TC_SNM23>
J 0
(-7700 3475);
FORCEPROP 1 LAST CUSTOM_TXT_CDS <CON_TC_SNM24>
J 0
(-7700 3375);
FORCEPROP 1 LAST CUSTOM_TXT_CDS <CON_TC_SNM25>
J 0
(-7700 3275);
FORCEPROP 1 LAST CUSTOM_TXT_CDS <CON_TC_SNM26>
J 0
(-7700 3175);
FORCEPROP 1 LAST CUSTOM_TXT_CDS <CON_TC_SNM27>
J 0
(-7700 3075);
FORCEPROP 1 LAST CUSTOM_TXT_CDS <CON_TC_SNM28>
J 0
(-7700 2975);
FORCEPROP 1 LAST CUSTOM_TXT_CDS <CON_TC_SNM29>
J 0
(-7700 2875);
FORCEPROP 1 LAST CUSTOM_TXT_CDS <CON_TC_SNM38>
J 0
(-7700 1975);
FORCEPROP 1 LAST CUSTOM_TXT_CDS <CON_TC_SNM39>
J 0
(-7700 1875);
FORCEPROP 1 LAST CUSTOM_TXT_CDS <CON_TC_SNM41>
J 0
(-5200 5675);
FORCEPROP 1 LAST CUSTOM_TXT_CDS <CON_TC_SNM42>
J 0
(-5200 5575);
FORCEPROP 1 LAST CUSTOM_TXT_CDS <CON_TC_SNM43>
J 0
(-5200 5475);
FORCEPROP 1 LAST CUSTOM_TXT_CDS <CON_TC_SNM44>
J 0
(-5200 5375);
FORCEPROP 1 LAST CUSTOM_TXT_CDS <CON_TC_SNM45>
J 0
(-5200 5275);
FORCEPROP 1 LAST CUSTOM_TXT_CDS <CON_TC_SNM46>
J 0
(-5200 5175);
FORCEPROP 1 LAST CUSTOM_TXT_CDS <CON_TC_SNM47>
J 0
(-5200 5075);
FORCEPROP 1 LAST CUSTOM_TXT_CDS <CON_TC_SNM48>
J 0
(-5200 4975);
FORCEPROP 1 LAST CUSTOM_TXT_CDS <CON_TC_SNM49>
J 0
(-5200 4875);
FORCEPROP 1 LAST CUSTOM_TXT_CDS <CON_TC_SNM50>
J 0
(-5200 4775);
FORCEPROP 1 LAST CUSTOM_TXT_CDS <CON_TC_SNM51>
J 0
(-5200 4675);
FORCEPROP 1 LAST CUSTOM_TXT_CDS <CON_TC_SNM52>
J 0
(-5200 4575);
FORCEPROP 1 LAST CUSTOM_TXT_CDS <CON_TC_SNM53>
J 0
(-5200 4475);
FORCEPROP 1 LAST CUSTOM_TXT_CDS <CON_TC_SNM54>
J 0
(-5200 4375);
FORCEPROP 1 LAST CUSTOM_TXT_CDS <CON_TC_SNM55>
J 0
(-5200 4275);
FORCEPROP 1 LAST CUSTOM_TXT_CDS <CON_TC_SNM56>
J 0
(-5200 4175);
FORCEPROP 1 LAST CUSTOM_TXT_CDS <CON_TC_SNM58>
J 0
(-5200 3975);
FORCEPROP 1 LAST CUSTOM_TXT_CDS <CON_TC_SNM59>
J 0
(-5200 3875);
FORCEPROP 1 LAST CUSTOM_TXT_CDS <CON_TC_SNM60>
J 0
(-5200 3775);
FORCEPROP 1 LAST CUSTOM_TXT_CDS <CON_TC_SNM61>
J 0
(-5200 3675);
FORCEPROP 1 LAST CUSTOM_TXT_CDS <CON_TC_SNM62>
J 0
(-5200 3575);
FORCEPROP 1 LAST CUSTOM_TXT_CDS <CON_TC_SNM64>
J 0
(-5200 3375);
FORCEPROP 1 LAST CUSTOM_TXT_CDS <CON_TC_SNM65>
J 0
(-5200 3275);
FORCEPROP 1 LAST CUSTOM_TXT_CDS <CON_TC_SNM66>
J 0
(-5200 3175);
FORCEPROP 1 LAST CUSTOM_TXT_CDS <CON_TC_SNM67>
J 0
(-5200 3075);
FORCEPROP 1 LAST CUSTOM_TXT_CDS <CON_TC_SNM68>
J 0
(-5200 2975);
FORCEPROP 1 LAST CUSTOM_TXT_CDS <CON_TC_SNM69>
J 0
(-5200 2875);
FORCEPROP 1 LAST CUSTOM_TXT_CDS <CON_TC_SNM70>
J 0
(-5200 2775);
FORCEPROP 1 LAST CUSTOM_TXT_CDS <CON_TC_SNM71>
J 0
(-5200 2675);
FORCEPROP 1 LAST CUSTOM_TXT_CDS <CON_TC_SNM72>
J 0
(-5200 2575);
FORCEPROP 1 LAST CUSTOM_TXT_CDS <CON_TC_SNM73>
J 0
(-5200 2475);
FORCEPROP 1 LAST CUSTOM_TXT_CDS <CON_TC_SNM81>
J 0
(-2700 5675);
FORCEPROP 1 LAST CUSTOM_TXT_CDS <CON_TC_SNM82>
J 0
(-2700 5575);
FORCEPROP 1 LAST CUSTOM_TXT_CDS <CON_TC_SNM83>
J 0
(-2700 5475);
FORCEPROP 1 LAST CUSTOM_TXT_CDS <CON_TC_SNM84>
J 0
(-2700 5375);
FORCEPROP 1 LAST CUSTOM_TXT_CDS <CON_TC_SNM85>
J 0
(-2700 5275);
FORCEPROP 1 LAST CUSTOM_TXT_CDS <CON_TC_SNM86>
J 0
(-2700 5175);
FORCEPROP 1 LAST CUSTOM_TXT_CDS <CON_TC_SNM87>
J 0
(-2700 5075);
FORCEPROP 1 LAST CUSTOM_TXT_CDS <CON_TC_SNM88>
J 0
(-2700 4975);
FORCEPROP 1 LAST CUSTOM_TXT_CDS <CON_TC_SNM89>
J 0
(-2700 4875);
FORCEPROP 1 LAST CUSTOM_TXT_CDS <CON_TC_SNM90>
J 0
(-2700 4775);
FORCEPROP 1 LAST CUSTOM_TXT_CDS <CON_TC_SNM91>
J 0
(-2700 4675);
FORCEPROP 1 LAST CUSTOM_TXT_CDS <CON_TC_SNM92>
J 0
(-2700 4575);
FORCEPROP 1 LAST CUSTOM_TXT_CDS <CON_TC_SNM93>
J 0
(-2700 4475);
FORCEPROP 1 LAST CUSTOM_TXT_CDS <CON_TC_SNM94>
J 0
(-2700 4375);
FORCEPROP 1 LAST CUSTOM_TXT_CDS <CON_TC_SNM95>
J 0
(-2700 4275);
FORCEPROP 1 LAST CUSTOM_TXT_CDS <CON_TC_SNM96>
J 0
(-2700 4175);
FORCEPROP 1 LAST CUSTOM_TXT_CDS <CON_TC_SNM97>
J 0
(-2700 4075);
FORCEPROP 1 LAST CUSTOM_TXT_CDS <CON_TC_SNM98>
J 0
(-2700 3975);
FORCEPROP 1 LAST CUSTOM_TXT_CDS <CON_TC_SNM99>
J 0
(-2700 3875);
FORCEPROP 1 LAST CUSTOM_TXT_CDS <CON_TC_SNM100>
J 0
(-2700 3775);
FORCEPROP 1 LAST CUSTOM_TXT_CDS <CON_TC_SNM101>
J 0
(-2700 3675);
FORCEPROP 1 LAST CUSTOM_TXT_CDS <CON_TC_SNM102>
J 0
(-2700 3575);
FORCEPROP 1 LAST CUSTOM_TXT_CDS <CON_TC_SNM103>
J 0
(-2700 3475);
FORCEPROP 1 LAST CUSTOM_TXT_CDS <CON_TC_SNM104>
J 0
(-2700 3375);
FORCEPROP 1 LAST CUSTOM_TXT_CDS <CON_TC_SNM105>
J 0
(-2700 3275);
FORCEPROP 1 LAST CUSTOM_TXT_CDS <CON_TC_SNM106>
J 0
(-2700 3175);
FORCEPROP 1 LAST CUSTOM_TXT_CDS <CON_TC_SNM107>
J 0
(-2700 3075);
FORCEPROP 1 LAST CUSTOM_TXT_CDS <CON_TC_SNM108>
J 0
(-2700 2975);
FORCEPROP 1 LAST CUSTOM_TXT_CDS <CON_TC_SNM109>
J 0
(-2700 2875);
FORCEPROP 1 LAST CUSTOM_TXT_CDS <CON_TC_SNM110>
J 0
(-2700 2775);
FORCEPROP 1 LAST CUSTOM_TXT_CDS <CON_TC_SNM111>
J 0
(-2700 2675);
FORCEPROP 1 LAST CUSTOM_TXT_CDS <CON_TC_SNM112>
J 0
(-2700 2575);
FORCEPROP 1 LAST CUSTOM_TXT_CDS <CON_TC_SNM113>
J 0
(-2700 2475);
FORCEPROP 1 LAST CUSTOM_TXT_CDS <CON_TC_SNM114>
J 0
(-2700 2375);
FORCEPROP 1 LAST CUSTOM_TXT_CDS <CON_TC_SNM115>
J 0
(-2700 2275);
FORCEPROP 1 LAST CUSTOM_TXT_CDS <CON_TC_SNM116>
J 0
(-2700 2175);
FORCEPROP 1 LAST CUSTOM_TXT_CDS <CON_TC_SNM117>
J 0
(-2700 2075);
FORCEPROP 1 LAST CUSTOM_TXT_CDS <CON_TC_SNM118>
J 0
(-2700 1975);
FORCEPROP 1 LAST CUSTOM_TXT_CDS <CON_TC_SNM120>
J 0
(-2700 1775);
FORCEPROP 1 LAST CUSTOM_TXT_CDS <CON_TC_SNO1>
J 2
(-7800 5675);
FORCEPROP 1 LAST CUSTOM_TXT_CDS <CON_TC_SNO2>
J 2
(-7800 5575);
FORCEPROP 1 LAST CUSTOM_TXT_CDS <CON_TC_SNO3>
J 2
(-7800 5475);
FORCEPROP 1 LAST CUSTOM_TXT_CDS <CON_TC_SNO4>
J 2
(-7800 5375);
FORCEPROP 1 LAST CUSTOM_TXT_CDS <CON_TC_SNO5>
J 2
(-7800 5275);
FORCEPROP 1 LAST CUSTOM_TXT_CDS <CON_TC_SNO6>
J 2
(-7800 5175);
FORCEPROP 1 LAST CUSTOM_TXT_CDS <CON_TC_SNO7>
J 2
(-7800 5075);
FORCEPROP 1 LAST CUSTOM_TXT_CDS <CON_TC_SNO8>
J 2
(-7800 4975);
FORCEPROP 1 LAST CUSTOM_TXT_CDS <CON_TC_SNO9>
J 2
(-7800 4875);
FORCEPROP 1 LAST CUSTOM_TXT_CDS <CON_TC_SNO10>
J 2
(-7800 4775);
FORCEPROP 1 LAST CUSTOM_TXT_CDS <CON_TC_SNO11>
J 2
(-7800 4675);
FORCEPROP 1 LAST CUSTOM_TXT_CDS <CON_TC_SNO12>
J 2
(-7800 4575);
FORCEPROP 1 LAST CUSTOM_TXT_CDS <CON_TC_SNO13>
J 2
(-7800 4475);
FORCEPROP 1 LAST CUSTOM_TXT_CDS <CON_TC_SNO14>
J 2
(-7800 4375);
FORCEPROP 1 LAST CUSTOM_TXT_CDS <CON_TC_SNO15>
J 2
(-7800 4275);
FORCEPROP 1 LAST CUSTOM_TXT_CDS <CON_TC_SNO16>
J 2
(-7800 4175);
FORCEPROP 1 LAST CUSTOM_TXT_CDS <CON_TC_SNO17>
J 2
(-7800 4075);
FORCEPROP 1 LAST CUSTOM_TXT_CDS <CON_TC_SNO18>
J 2
(-7800 3975);
FORCEPROP 1 LAST CUSTOM_TXT_CDS <CON_TC_SNO19>
J 2
(-7800 3875);
FORCEPROP 1 LAST CUSTOM_TXT_CDS <CON_TC_SNO20>
J 2
(-7800 3775);
FORCEPROP 1 LAST CUSTOM_TXT_CDS <CON_TC_SNO21>
J 2
(-7800 3675);
FORCEPROP 1 LAST CUSTOM_TXT_CDS <CON_TC_SNO22>
J 2
(-7800 3575);
FORCEPROP 1 LAST CUSTOM_TXT_CDS <CON_TC_SNO23>
J 2
(-7800 3475);
FORCEPROP 1 LAST CUSTOM_TXT_CDS <CON_TC_SNO24>
J 2
(-7800 3375);
FORCEPROP 1 LAST CUSTOM_TXT_CDS <CON_TC_SNO25>
J 2
(-7800 3275);
FORCEPROP 1 LAST CUSTOM_TXT_CDS <CON_TC_SNO26>
J 2
(-7800 3175);
FORCEPROP 1 LAST CUSTOM_TXT_CDS <CON_TC_SNO27>
J 2
(-7800 3075);
FORCEPROP 1 LAST CUSTOM_TXT_CDS <CON_TC_SNO28>
J 2
(-7800 2975);
FORCEPROP 1 LAST CUSTOM_TXT_CDS <CON_TC_SNO30>
J 2
(-7800 2775);
FORCEPROP 1 LAST CUSTOM_TXT_CDS <CON_TC_SNO31>
J 2
(-7800 2675);
FORCEPROP 1 LAST CUSTOM_TXT_CDS <CON_TC_SNO32>
J 2
(-7800 2575);
FORCEPROP 1 LAST CUSTOM_TXT_CDS <CON_TC_SNO33>
J 2
(-7800 2475);
FORCEPROP 1 LAST CUSTOM_TXT_CDS <CON_TC_SNO34>
J 2
(-7800 2375);
FORCEPROP 1 LAST CUSTOM_TXT_CDS <CON_TC_SNO35>
J 2
(-7800 2275);
FORCEPROP 1 LAST CUSTOM_TXT_CDS <CON_TC_SNO36>
J 2
(-7800 2175);
FORCEPROP 1 LAST CUSTOM_TXT_CDS <CON_TC_SNO37>
J 2
(-7800 2075);
FORCEPROP 1 LAST CUSTOM_TXT_CDS <CON_TC_SNO38>
J 2
(-7800 1975);
FORCEPROP 1 LAST CUSTOM_TXT_CDS <CON_TC_SNO39>
J 2
(-7800 1875);
FORCEPROP 1 LAST CUSTOM_TXT_CDS <CON_TC_SNO40>
J 2
(-7800 1775);
FORCEPROP 1 LAST CUSTOM_TXT_CDS <CON_TC_SNO41>
J 2
(-5300 5675);
FORCEPROP 1 LAST CUSTOM_TXT_CDS <CON_TC_SNO42>
J 2
(-5300 5575);
FORCEPROP 1 LAST CUSTOM_TXT_CDS <CON_TC_SNO43>
J 2
(-5300 5475);
FORCEPROP 1 LAST CUSTOM_TXT_CDS <CON_TC_SNO44>
J 2
(-5300 5375);
FORCEPROP 1 LAST CUSTOM_TXT_CDS <CON_TC_SNO45>
J 2
(-5300 5275);
FORCEPROP 1 LAST CUSTOM_TXT_CDS <CON_TC_SNO46>
J 2
(-5300 5175);
FORCEPROP 1 LAST CUSTOM_TXT_CDS <CON_TC_SNO47>
J 2
(-5300 5075);
FORCEPROP 1 LAST CUSTOM_TXT_CDS <CON_TC_SNO48>
J 2
(-5300 4975);
FORCEPROP 1 LAST CUSTOM_TXT_CDS <CON_TC_SNO49>
J 2
(-5300 4875);
FORCEPROP 1 LAST CUSTOM_TXT_CDS <CON_TC_SNO50>
J 2
(-5300 4775);
FORCEPROP 1 LAST CUSTOM_TXT_CDS <CON_TC_SNO51>
J 2
(-5300 4675);
FORCEPROP 1 LAST CUSTOM_TXT_CDS <CON_TC_SNO52>
J 2
(-5300 4575);
FORCEPROP 1 LAST CUSTOM_TXT_CDS <CON_TC_SNO53>
J 2
(-5300 4475);
FORCEPROP 1 LAST CUSTOM_TXT_CDS <CON_TC_SNO54>
J 2
(-5300 4375);
FORCEPROP 1 LAST CUSTOM_TXT_CDS <CON_TC_SNO55>
J 2
(-5300 4275);
FORCEPROP 1 LAST CUSTOM_TXT_CDS <CON_TC_SNO56>
J 2
(-5300 4175);
FORCEPROP 1 LAST CUSTOM_TXT_CDS <CON_TC_SNO57>
J 2
(-5300 4075);
FORCEPROP 1 LAST CUSTOM_TXT_CDS <CON_TC_SNO58>
J 2
(-5300 3975);
FORCEPROP 1 LAST CUSTOM_TXT_CDS <CON_TC_SNO59>
J 2
(-5300 3875);
FORCEPROP 1 LAST CUSTOM_TXT_CDS <CON_TC_SNO60>
J 2
(-5300 3775);
FORCEPROP 1 LAST CUSTOM_TXT_CDS <CON_TC_SNO61>
J 2
(-5300 3675);
FORCEPROP 1 LAST CUSTOM_TXT_CDS <CON_TC_SNO62>
J 2
(-5300 3575);
FORCEPROP 1 LAST CUSTOM_TXT_CDS <CON_TC_SNO63>
J 2
(-5300 3475);
FORCEPROP 1 LAST CUSTOM_TXT_CDS <CON_TC_SNO64>
J 2
(-5300 3375);
FORCEPROP 1 LAST CUSTOM_TXT_CDS <CON_TC_SNO65>
J 2
(-5300 3275);
FORCEPROP 1 LAST CUSTOM_TXT_CDS <CON_TC_SNO66>
J 2
(-5300 3175);
FORCEPROP 1 LAST CUSTOM_TXT_CDS <CON_TC_SNO67>
J 2
(-5300 3075);
FORCEPROP 1 LAST CUSTOM_TXT_CDS <CON_TC_SNO68>
J 2
(-5300 2975);
FORCEPROP 1 LAST CUSTOM_TXT_CDS <CON_TC_SNO69>
J 2
(-5300 2875);
FORCEPROP 1 LAST CUSTOM_TXT_CDS <CON_TC_SNO70>
J 2
(-5300 2775);
FORCEPROP 1 LAST CUSTOM_TXT_CDS <CON_TC_SNO71>
J 2
(-5300 2675);
FORCEPROP 1 LAST CUSTOM_TXT_CDS <CON_TC_SNO72>
J 2
(-5300 2575);
FORCEPROP 1 LAST CUSTOM_TXT_CDS <CON_TC_SNO73>
J 2
(-5300 2475);
FORCEPROP 1 LAST CUSTOM_TXT_CDS <CON_TC_SNO76>
J 2
(-5300 2175);
FORCEPROP 1 LAST CUSTOM_TXT_CDS <CON_TC_SNO80>
J 2
(-5300 1775);
FORCEPROP 1 LAST CUSTOM_TXT_CDS <CON_TC_SNO81>
J 2
(-2800 5675);
FORCEPROP 1 LAST CUSTOM_TXT_CDS <CON_TC_SNO83>
J 2
(-2800 5475);
FORCEPROP 1 LAST CUSTOM_TXT_CDS <CON_TC_SNO84>
J 2
(-2800 5375);
FORCEPROP 1 LAST CUSTOM_TXT_CDS <CON_TC_SNO85>
J 2
(-2800 5275);
FORCEPROP 1 LAST CUSTOM_TXT_CDS <CON_TC_SNO86>
J 2
(-2800 5175);
FORCEPROP 1 LAST CUSTOM_TXT_CDS <CON_TC_SNO87>
J 2
(-2800 5075);
FORCEPROP 1 LAST CUSTOM_TXT_CDS <CON_TC_SNO88>
J 2
(-2800 4975);
FORCEPROP 1 LAST CUSTOM_TXT_CDS <CON_TC_SNO89>
J 2
(-2800 4875);
FORCEPROP 1 LAST CUSTOM_TXT_CDS <CON_TC_SNO90>
J 2
(-2800 4775);
FORCEPROP 1 LAST CUSTOM_TXT_CDS <CON_TC_SNO91>
J 2
(-2800 4675);
FORCEPROP 1 LAST CUSTOM_TXT_CDS <CON_TC_SNO92>
J 2
(-2800 4575);
FORCEPROP 1 LAST CUSTOM_TXT_CDS <CON_TC_SNO93>
J 2
(-2800 4475);
FORCEPROP 1 LAST CUSTOM_TXT_CDS <CON_TC_SNO94>
J 2
(-2800 4375);
FORCEPROP 1 LAST CUSTOM_TXT_CDS <CON_TC_SNO95>
J 2
(-2800 4275);
FORCEPROP 1 LAST CUSTOM_TXT_CDS <CON_TC_SNO96>
J 2
(-2800 4175);
FORCEPROP 1 LAST CUSTOM_TXT_CDS <CON_TC_SNO97>
J 2
(-2800 4075);
FORCEPROP 1 LAST CUSTOM_TXT_CDS <CON_TC_SNO98>
J 2
(-2800 3975);
FORCEPROP 1 LAST CUSTOM_TXT_CDS <CON_TC_SNO99>
J 2
(-2800 3875);
FORCEPROP 1 LAST CUSTOM_TXT_CDS <CON_TC_SNO100>
J 2
(-2800 3775);
FORCEPROP 1 LAST CUSTOM_TXT_CDS <CON_TC_SNO101>
J 2
(-2800 3675);
FORCEPROP 1 LAST CUSTOM_TXT_CDS <CON_TC_SNO102>
J 2
(-2800 3575);
FORCEPROP 1 LAST CUSTOM_TXT_CDS <CON_TC_SNO103>
J 2
(-2800 3475);
FORCEPROP 1 LAST CUSTOM_TXT_CDS <CON_TC_SNO104>
J 2
(-2800 3375);
FORCEPROP 1 LAST CUSTOM_TXT_CDS <CON_TC_SNO105>
J 2
(-2800 3275);
FORCEPROP 1 LAST CUSTOM_TXT_CDS <CON_TC_SNO106>
J 2
(-2800 3175);
FORCEPROP 1 LAST CUSTOM_TXT_CDS <CON_TC_SNO107>
J 2
(-2800 3075);
FORCEPROP 1 LAST CUSTOM_TXT_CDS <CON_TC_SNO108>
J 2
(-2800 2975);
FORCEPROP 1 LAST CUSTOM_TXT_CDS <CON_TC_SNO109>
J 2
(-2800 2875);
FORCEPROP 1 LAST CUSTOM_TXT_CDS <CON_TC_SNO110>
J 2
(-2800 2775);
FORCEPROP 1 LAST CUSTOM_TXT_CDS <CON_TC_SNO111>
J 2
(-2800 2675);
FORCEPROP 1 LAST CUSTOM_TXT_CDS <CON_TC_SNO112>
J 2
(-2800 2575);
FORCEPROP 1 LAST CUSTOM_TXT_CDS <CON_TC_SNO113>
J 2
(-2800 2475);
FORCEPROP 1 LAST CUSTOM_TXT_CDS <CON_TC_SNO114>
J 2
(-2800 2375);
FORCEPROP 1 LAST CUSTOM_TXT_CDS <CON_TC_SNO116>
J 2
(-2800 2175);
FORCEPROP 1 LAST CUSTOM_TXT_CDS <CON_TC_SNO117>
J 2
(-2800 2075);
FORCEPROP 1 LAST CUSTOM_TXT_CDS <CON_TC_SNO118>
J 2
(-2800 1975);
FORCEPROP 1 LAST CUSTOM_TXT_CDS <CON_TC_SNO119>
J 2
(-2800 1875);
FORCEPROP 1 LAST CUSTOM_TXT_CDS <CON_TC_SNO120>
J 2
(-2800 1775);
FORCEPROP 1 LAST CUSTOM_TXT_CDS <CON_TC_SNO29>
J 2
(-7800 2875);
FORCEPROP 1 LAST CUSTOM_TXT_CDS <CON_TC_SNM30>
J 0
(-7700 2775);
FORCEPROP 1 LAST CUSTOM_TXT_CDS <CON_TC_SNM31>
J 0
(-7700 2675);
FORCEPROP 1 LAST CUSTOM_TXT_CDS <CON_TC_SNM32>
J 0
(-7700 2575);
FORCEPROP 1 LAST CUSTOM_TXT_CDS <CON_TC_SNM33>
J 0
(-7700 2475);
FORCEPROP 1 LAST CUSTOM_TXT_CDS <CON_TC_SNM34>
J 0
(-7700 2375);
FORCEPROP 2 LAST CUSTOM_TXT_CDS <NAME_2>
J 0
(-3325 150);
DISPLAY 1.021277 (-3325 150);
FORCEPROP 2 LAST CUSTOM_TXT_CDS <NAME_1>
J 0
(-3325 275);
DISPLAY 1.021277 (-3325 275);
FORCEPROP 1 LAST CUSTOM_TXT_CDS <CON_TC_SNM79>
J 0
(-5200 1875);
FORCEPROP 1 LAST CUSTOM_TXT_CDS <CON_TC_SNM74>
J 0
(-5200 2375);
FORCEPROP 1 LAST CUSTOM_TXT_CDS <CON_TC_SNM75>
J 0
(-5200 2275);
FORCEPROP 1 LAST CUSTOM_TXT_CDS <CON_TC_SNM76>
J 0
(-5200 2175);
FORCEPROP 1 LAST CUSTOM_TXT_CDS <CON_TC_SNM80>
J 0
(-5200 1775);
FORCEPROP 1 LAST CUSTOM_TXT_CDS <CON_TC_SNO79>
J 2
(-5300 1875);
FORCEPROP 1 LAST CUSTOM_TXT_CDS <CON_TC_SNO78>
J 2
(-5300 1975);
FORCEPROP 2 LAST CDS_LIB pure_quanta
J 0
(-100 100);
DISPLAY INVISIBLE (-100 100);
FORCEPROP 2 LAST PAGE_BORDER TRUE
J 0
(-7990 5350);
DISPLAY 0.638298 (-7990 5350);
PAINT PINK (-7990 5350);
DISPLAY INVISIBLE (-7990 5350);
FORCEPROP 1 LAST TOC_SYMBOL TRUE
J 0
(-9274 6552);
DISPLAY 0.978723 (-9274 6552);
PAINT GREEN (-9274 6552);
DISPLAY INVISIBLE (-9274 6552);
FORCEPROP 2 LAST CDS_XR_PAGE_TITLE CR-2 : @T6G_MB_LIB.T6G(SCH_1):PAGE2
J 0
(-7990 5350);
DISPLAY 0.638298 (-7990 5350);
PAINT PINK (-7990 5350);
DISPLAY INVISIBLE (-7990 5350);
FORCEPROP 2 LAST CUSTOM_TXT_CDS <XR_PAGE_TITLE>
J 0
(-7990 5350);
DISPLAY 0.638298 (-7990 5350);
PAINT PINK (-7990 5350);
DISPLAY INVISIBLE (-7990 5350);
FORCEPROP 1 LAST COMMENT_BODY TRUE
J 0
(-1249 126);
DISPLAY 0.978723 (-1249 126);
PAINT GREEN (-1249 126);
DISPLAY INVISIBLE (-1249 126);
FORCEPROP 1 LAST Q_DEPT BU9
J 1
(-3851 149);
DISPLAY 1.957447 (-3851 149);
PAINT GREEN (-3851 149);
DISPLAY INVISIBLE (-3851 149);
FORCEPROP 0 LAST CDS_CON_LAST_MODIFIED Thu Aug 24 10:13:29 2023
J 0
(-2000 125);
DISPLAY INVISIBLE (-2000 125);
QUIT
